(kicad_pcb
	(version 20260206)
	(generator "pcbnew")
	(generator_version "10.0")
	(general
		(thickness 1.6)
		(legacy_teardrops no)
	)
	(paper "A4")
	(title_block
		(title "04192023_DAF0TMB3IC0_F0TG_MB_C_brd_V02_OCP.brd")
		(comment 1 "Grand Teton / footprints 387-390 of 8354")
	)
	(layers
		(0 "F.Cu" signal "TOP")
		(4 "In1.Cu" signal "GND")
		(6 "In2.Cu" signal "IN1")
		(8 "In3.Cu" signal "GND1")
		(10 "In4.Cu" signal "IN2")
		(12 "In5.Cu" signal "GND2")
		(14 "In6.Cu" signal "IN3")
		(16 "In7.Cu" signal "GND3")
		(18 "In8.Cu" signal "VCC")
		(20 "In9.Cu" signal "VCC1")
		(22 "In10.Cu" signal "GND4")
		(24 "In11.Cu" signal "IN4")
		(26 "In12.Cu" signal "GND5")
		(28 "In13.Cu" signal "IN5")
		(30 "In14.Cu" signal "GND6")
		(32 "In15.Cu" signal "IN6")
		(34 "In16.Cu" signal "GND7")
		(2 "B.Cu" signal "BOTTOM")
		(9 "F.Adhes" user "F.Adhesive")
		(11 "B.Adhes" user "B.Adhesive")
		(13 "F.Paste" user "Package Geometry/Pastemask Top")
		(15 "B.Paste" user "Package Geometry/Pastemask Bottom")
		(5 "F.SilkS" user "Ref Des/Silkscreen Top")
		(7 "B.SilkS" user "Ref Des/Silkscreen Bottom")
		(1 "F.Mask" user "Board Geometry/Soldermask Top")
		(3 "B.Mask" user "Board Geometry/Soldermask Bottom")
		(17 "Dwgs.User" user "User.Drawings")
		(19 "Cmts.User" user "User.Comments")
		(21 "Eco1.User" user "User.Eco1")
		(23 "Eco2.User" user "User.Eco2")
		(25 "Edge.Cuts" user "Board Geometry/Outline")
		(27 "Margin" user)
		(31 "F.CrtYd" user "Package Geometry/Place Bound Top")
		(29 "B.CrtYd" user "Package Geometry/Place Bound Bottom")
		(35 "F.Fab" user "Ref Des/Assembly Top")
		(33 "B.Fab" user "Ref Des/Assembly Bottom")
	)
	(footprint ""
		(layer "F.Cu")
		(at 159.741108 -344.706956)
		(property "Reference" "PC639"
			(at 0 0 0)
			(layer "F.SilkS")
			(hide yes)
			(effects
				(font
					(size 1.27 1.27)
				)
			)
		)
		(property "Value" ""
			(at 0 0 0)
			(layer "F.Fab")
			(effects
				(font
					(size 1.27 1.27)
				)
			)
		)
		(duplicate_pad_numbers_are_jumpers no)
		(fp_line
			(start -0.7874 -0.4064)
			(end 0.7874 -0.4064)
			(stroke
				(width 0.1524)
				(type default)
			)
			(layer "F.SilkS")
		)
		(fp_line
			(start -0.7874 0.4064)
			(end -0.7874 -0.4064)
			(stroke
				(width 0.1524)
				(type default)
			)
			(layer "F.SilkS")
		)
		(fp_line
			(start 0.7874 -0.4064)
			(end 0.7874 0.4064)
			(stroke
				(width 0.1524)
				(type default)
			)
			(layer "F.SilkS")
		)
		(fp_line
			(start 0.7874 0.4064)
			(end -0.7874 0.4064)
			(stroke
				(width 0.1524)
				(type default)
			)
			(layer "F.SilkS")
		)
		(fp_line
			(start -0.67945 -0.305054)
			(end -0.12065 -0.305054)
			(stroke
				(width 0.1)
				(type default)
			)
			(layer "F.Fab")
		)
		(fp_line
			(start -0.67945 0.3048)
			(end -0.67945 -0.305054)
			(stroke
				(width 0.1)
				(type default)
			)
			(layer "F.Fab")
		)
		(fp_line
			(start -0.12065 -0.305054)
			(end -0.12065 -0.2794)
			(stroke
				(width 0.1)
				(type default)
			)
			(layer "F.Fab")
		)
		(fp_line
			(start -0.12065 -0.2794)
			(end 0.12065 -0.2794)
			(stroke
				(width 0.1)
				(type default)
			)
			(layer "F.Fab")
		)
		(fp_line
			(start -0.12065 0.2794)
			(end -0.12065 0.3048)
			(stroke
				(width 0.1)
				(type default)
			)
			(layer "F.Fab")
		)
		(fp_line
			(start -0.12065 0.3048)
			(end -0.67945 0.3048)
			(stroke
				(width 0.1)
				(type default)
			)
			(layer "F.Fab")
		)
		(fp_line
			(start 0.120396 0.2794)
			(end -0.12065 0.2794)
			(stroke
				(width 0.1)
				(type default)
			)
			(layer "F.Fab")
		)
		(fp_line
			(start 0.120396 0.3048)
			(end 0.120396 0.2794)
			(stroke
				(width 0.1)
				(type default)
			)
			(layer "F.Fab")
		)
		(fp_line
			(start 0.12065 -0.3048)
			(end 0.67945 -0.3048)
			(stroke
				(width 0.1)
				(type default)
			)
			(layer "F.Fab")
		)
		(fp_line
			(start 0.12065 -0.2794)
			(end 0.12065 -0.3048)
			(stroke
				(width 0.1)
				(type default)
			)
			(layer "F.Fab")
		)
		(fp_line
			(start 0.67945 -0.3048)
			(end 0.67945 0.3048)
			(stroke
				(width 0.1)
				(type default)
			)
			(layer "F.Fab")
		)
		(fp_line
			(start 0.67945 0.3048)
			(end 0.120396 0.3048)
			(stroke
				(width 0.1)
				(type default)
			)
			(layer "F.Fab")
		)
		(pad "1" smd circle
			(at -0.40005 0)
			(size 0 0)
			(layers "F.Cu" "F.Mask" "F.Paste")
			(net "VSENSE_PVDD11_S3_P1_R")
		)
		(pad "2" smd circle
			(at 0.40005 0)
			(size 0 0)
			(layers "F.Cu" "F.Mask" "F.Paste")
			(net "VSENSE_VSS_SENSE_C_P1")
		)
	)
	(footprint ""
		(layer "F.Cu")
		(at 444.136018 -76.107798)
		(property "Reference" "C1340"
			(at 0 0 0)
			(layer "F.SilkS")
			(hide yes)
			(effects
				(font
					(size 1.27 1.27)
				)
			)
		)
		(property "Value" ""
			(at 0 0 0)
			(layer "F.Fab")
			(effects
				(font
					(size 1.27 1.27)
				)
			)
		)
		(duplicate_pad_numbers_are_jumpers no)
		(fp_line
			(start -1.524 -0.762)
			(end 1.524 -0.762)
			(stroke
				(width 0.1524)
				(type default)
			)
			(layer "F.SilkS")
		)
		(fp_line
			(start -1.524 0.762)
			(end -1.524 -0.762)
			(stroke
				(width 0.1524)
				(type default)
			)
			(layer "F.SilkS")
		)
		(fp_line
			(start 1.524 -0.762)
			(end 1.524 0.762)
			(stroke
				(width 0.1524)
				(type default)
			)
			(layer "F.SilkS")
		)
		(fp_line
			(start 1.524 0.762)
			(end -1.524 0.762)
			(stroke
				(width 0.1524)
				(type default)
			)
			(layer "F.SilkS")
		)
		(fp_line
			(start -1.1049 -0.724916)
			(end -1.1049 0.724916)
			(stroke
				(width 0.1)
				(type default)
			)
			(layer "F.Fab")
		)
		(fp_line
			(start -1.1049 0.724916)
			(end 1.1049 0.724916)
			(stroke
				(width 0.1)
				(type default)
			)
			(layer "F.Fab")
		)
		(fp_line
			(start 1.1049 -0.724916)
			(end -1.1049 -0.724916)
			(stroke
				(width 0.1)
				(type default)
			)
			(layer "F.Fab")
		)
		(fp_line
			(start 1.1049 0.724916)
			(end 1.1049 -0.724916)
			(stroke
				(width 0.1)
				(type default)
			)
			(layer "F.Fab")
		)
		(pad "1" smd rect
			(at -0.889 0 180)
			(size 1.016 1.27)
			(layers "F.Cu" "F.Mask" "F.Paste")
			(net "P3V3")
		)
		(pad "2" smd rect
			(at 0.889 0 180)
			(size 1.016 1.27)
			(layers "F.Cu" "F.Mask" "F.Paste")
			(net "GND")
		)
	)
	(footprint ""
		(layer "F.Cu")
		(at 69.33057 -166.26332 -90)
		(property "Reference" "PC125"
			(at 0 0 270)
			(layer "F.SilkS")
			(hide yes)
			(effects
				(font
					(size 1.27 1.27)
				)
			)
		)
		(property "Value" ""
			(at 0 0 270)
			(layer "F.Fab")
			(effects
				(font
					(size 1.27 1.27)
				)
			)
		)
		(duplicate_pad_numbers_are_jumpers no)
		(fp_line
			(start -0.7874 0.4064)
			(end -0.7874 -0.4064)
			(stroke
				(width 0.1524)
				(type default)
			)
			(layer "F.SilkS")
		)
		(fp_line
			(start -0.36068 0.4064)
			(end -0.7874 0.4064)
			(stroke
				(width 0.1524)
				(type default)
			)
			(layer "F.SilkS")
		)
		(fp_line
			(start 0.7874 0.4064)
			(end 0.50292 0.4064)
			(stroke
				(width 0.1524)
				(type default)
			)
			(layer "F.SilkS")
		)
		(fp_line
			(start -0.7874 -0.4064)
			(end 0.7874 -0.4064)
			(stroke
				(width 0.1524)
				(type default)
			)
			(layer "F.SilkS")
		)
		(fp_line
			(start 0.7874 -0.4064)
			(end 0.7874 0.4064)
			(stroke
				(width 0.1524)
				(type default)
			)
			(layer "F.SilkS")
		)
		(fp_line
			(start -0.67945 0.3048)
			(end -0.67945 -0.305054)
			(stroke
				(width 0.1)
				(type default)
			)
			(layer "F.Fab")
		)
		(fp_line
			(start -0.12065 0.3048)
			(end -0.67945 0.3048)
			(stroke
				(width 0.1)
				(type default)
			)
			(layer "F.Fab")
		)
		(fp_line
			(start 0.120396 0.3048)
			(end 0.120396 0.2794)
			(stroke
				(width 0.1)
				(type default)
			)
			(layer "F.Fab")
		)
		(fp_line
			(start 0.67945 0.3048)
			(end 0.120396 0.3048)
			(stroke
				(width 0.1)
				(type default)
			)
			(layer "F.Fab")
		)
		(fp_line
			(start -0.12065 0.2794)
			(end -0.12065 0.3048)
			(stroke
				(width 0.1)
				(type default)
			)
			(layer "F.Fab")
		)
		(fp_line
			(start 0.120396 0.2794)
			(end -0.12065 0.2794)
			(stroke
				(width 0.1)
				(type default)
			)
			(layer "F.Fab")
		)
		(fp_line
			(start -0.12065 -0.2794)
			(end 0.12065 -0.2794)
			(stroke
				(width 0.1)
				(type default)
			)
			(layer "F.Fab")
		)
		(fp_line
			(start 0.12065 -0.2794)
			(end 0.12065 -0.3048)
			(stroke
				(width 0.1)
				(type default)
			)
			(layer "F.Fab")
		)
		(fp_line
			(start 0.12065 -0.3048)
			(end 0.67945 -0.3048)
			(stroke
				(width 0.1)
				(type default)
			)
			(layer "F.Fab")
		)
		(fp_line
			(start 0.67945 -0.3048)
			(end 0.67945 0.3048)
			(stroke
				(width 0.1)
				(type default)
			)
			(layer "F.Fab")
		)
		(fp_line
			(start -0.67945 -0.305054)
			(end -0.12065 -0.305054)
			(stroke
				(width 0.1)
				(type default)
			)
			(layer "F.Fab")
		)
		(fp_line
			(start -0.12065 -0.305054)
			(end -0.12065 -0.2794)
			(stroke
				(width 0.1)
				(type default)
			)
			(layer "F.Fab")
		)
		(pad "1" smd circle
			(at -0.40005 0 270)
			(size 0 0)
			(layers "F.Cu" "F.Mask" "F.Paste")
			(net "PVDDCR_CPU0_P1_VCC6")
		)
		(pad "2" smd circle
			(at 0.40005 0 270)
			(size 0 0)
			(layers "F.Cu" "F.Mask" "F.Paste")
			(net "GND")
		)
	)
	(footprint ""
		(layer "F.Cu")
		(at 195.88988 -383.160524 180)
		(property "Reference" "PJ38"
			(at 4.616196 4.675886 90)
			(unlocked yes)
			(layer "F.SilkS")
			(effects
				(font
					(size 0.7874 0.5842)
					(thickness 0.1524)
				)
				(justify left)
			)
		)
		(property "Value" ""
			(at 0 0 180)
			(layer "F.Fab")
			(effects
				(font
					(size 1.27 1.27)
				)
			)
		)
		(duplicate_pad_numbers_are_jumpers no)
		(fp_line
			(start 2.500122 7.649972)
			(end -2.500122 7.649972)
			(stroke
				(width 0.1524)
				(type default)
			)
			(layer "F.SilkS")
		)
		(fp_line
			(start 2.500122 7.570978)
			(end 2.500122 7.649972)
			(stroke
				(width 0.1524)
				(type default)
			)
			(layer "F.SilkS")
		)
		(fp_line
			(start 2.500122 4.944618)
			(end 2.500122 5.869178)
			(stroke
				(width 0.1524)
				(type default)
			)
			(layer "F.SilkS")
		)
		(fp_line
			(start 2.500122 -5.869178)
			(end 2.500122 -4.944618)
			(stroke
				(width 0.1524)
				(type default)
			)
			(layer "F.SilkS")
		)
		(fp_line
			(start 2.500122 -7.649972)
			(end 2.500122 -7.570978)
			(stroke
				(width 0.1524)
				(type default)
			)
			(layer "F.SilkS")
		)
		(fp_line
			(start -2.500122 7.649972)
			(end -2.500122 7.570978)
			(stroke
				(width 0.1524)
				(type default)
			)
			(layer "F.SilkS")
		)
		(fp_line
			(start -2.500122 5.869178)
			(end -2.500122 5.44449)
			(stroke
				(width 0.1524)
				(type default)
			)
			(layer "F.SilkS")
		)
		(fp_line
			(start -2.500122 -5.44449)
			(end -2.500122 -5.869178)
			(stroke
				(width 0.1524)
				(type default)
			)
			(layer "F.SilkS")
		)
		(fp_line
			(start -2.500122 -7.570978)
			(end -2.500122 -7.649972)
			(stroke
				(width 0.1524)
				(type default)
			)
			(layer "F.SilkS")
		)
		(fp_line
			(start -2.500122 -7.649972)
			(end 2.500122 -7.649972)
			(stroke
				(width 0.1524)
				(type default)
			)
			(layer "F.SilkS")
		)
		(fp_poly
			(pts
				(xy -3.078988 -4.99999) (xy -4.094988 -4.49199) (xy -4.094988 -5.50799)
			)
			(stroke
				(width 0)
				(type default)
			)
			(fill yes)
			(layer "F.SilkS")
		)
		(fp_line
			(start 2.500122 7.649972)
			(end -2.500122 7.649972)
			(stroke
				(width 0.1)
				(type default)
			)
			(layer "F.Fab")
		)
		(fp_line
			(start 2.500122 -7.649972)
			(end 2.500122 7.649972)
			(stroke
				(width 0.1)
				(type default)
			)
			(layer "F.Fab")
		)
		(fp_line
			(start -2.500122 7.649972)
			(end -2.500122 -7.649972)
			(stroke
				(width 0.1)
				(type default)
			)
			(layer "F.Fab")
		)
		(fp_line
			(start -2.500122 -7.649972)
			(end 2.500122 -7.649972)
			(stroke
				(width 0.1)
				(type default)
			)
			(layer "F.Fab")
		)
		(fp_poly
			(pts
				(xy -4.094988 -5.50799) (xy -4.094988 -4.49199) (xy -3.078988 -4.99999)
			)
			(stroke
				(width 0)
				(type default)
			)
			(fill yes)
			(layer "F.Fab")
		)
		(pad "" np_thru_hole circle
			(at 1.100074 -5.5245 90)
			(size 0.762 0.762)
			(drill 0.762)
			(layers "*.Cu" "*.Mask")
			(clearance 0.381)
			(thermal_gap 0.381)
		)
		(pad "" np_thru_hole circle
			(at 1.100074 5.5245 90)
			(size 0.762 0.762)
			(drill 0.762)
			(layers "*.Cu" "*.Mask")
			(clearance 0.381)
			(thermal_gap 0.381)
		)
		(pad "1" smd rect
			(at -2.109978 -4.99999 270)
			(size 0.6096 1.651)
			(layers "F.Cu" "F.Mask" "F.Paste")
			(net "P12V_PSU")
		)
		(pad "2" smd rect
			(at -2.109978 -3.999992 270)
			(size 0.6096 1.651)
			(layers "F.Cu" "F.Mask" "F.Paste")
			(net "P12V_HSC_SENSE1_P")
		)
		(pad "3" smd rect
			(at -2.109978 -2.999994 270)
			(size 0.6096 1.651)
			(layers "F.Cu" "F.Mask" "F.Paste")
			(net "P12V_HSC_SENSE1_N")
		)
		(pad "4" smd rect
			(at -2.109978 -1.999996 270)
			(size 0.6096 1.651)
			(layers "F.Cu" "F.Mask" "F.Paste")
			(net "P12V_HSC_SENSE2_P")
		)
		(pad "5" smd rect
			(at -2.109978 -0.999998 270)
			(size 0.6096 1.651)
			(layers "F.Cu" "F.Mask" "F.Paste")
			(net "P12V_HSC_SENSE2_N")
		)
		(pad "6" smd rect
			(at -2.109978 0 270)
			(size 0.6096 1.651)
			(layers "F.Cu" "F.Mask" "F.Paste")
			(net "P12V_HSC_ADC_N")
		)
		(pad "7" smd rect
			(at -2.109978 0.999998 270)
			(size 0.6096 1.651)
			(layers "F.Cu" "F.Mask" "F.Paste")
			(net "P12V_HSC_ADC_P")
		)
		(pad "8" smd rect
			(at -2.109978 1.999996 270)
			(size 0.6096 1.651)
			(layers "F.Cu" "F.Mask" "F.Paste")
			(net "P12V_HSC_GATE1")
		)
		(pad "9" smd rect
			(at -2.109978 2.999994 270)
			(size 0.6096 1.651)
			(layers "F.Cu" "F.Mask" "F.Paste")
			(net "P12V_HSC_GATE2")
		)
		(pad "10" smd rect
			(at -2.109978 3.999992 270)
			(size 0.6096 1.651)
			(layers "F.Cu" "F.Mask" "F.Paste")
			(net "P12V_AUX")
		)
		(pad "11" smd rect
			(at -2.109978 4.99999 270)
			(size 0.6096 1.651)
			(layers "F.Cu" "F.Mask" "F.Paste")
			(net "GND")
		)
		(pad "12" smd rect
			(at 2.109978 -4.500118 90)
			(size 0.6096 1.651)
			(layers "F.Cu" "F.Mask" "F.Paste")
			(net "P3V3_AUX")
		)
		(pad "13" smd rect
			(at 2.109978 -3.50012 90)
			(size 0.6096 1.651)
			(layers "F.Cu" "F.Mask" "F.Paste")
			(net "IRQ_HSC_FAULT_N")
		)
		(pad "14" smd rect
			(at 2.109978 -2.500122 90)
			(size 0.6096 1.651)
			(layers "F.Cu" "F.Mask" "F.Paste")
			(net "HSC_EN")
		)
		(pad "15" smd rect
			(at 2.109978 -1.500124 90)
			(size 0.6096 1.651)
			(layers "F.Cu" "F.Mask" "F.Paste")
			(net "MB0_P12V_STBY_PWRGD")
		)
		(pad "16" smd rect
			(at 2.109978 -0.499872 90)
			(size 0.6096 1.651)
			(layers "F.Cu" "F.Mask" "F.Paste")
			(net "HSC_CSOUT")
		)
		(pad "17" smd rect
			(at 2.109978 0.499872 90)
			(size 0.6096 1.651)
			(layers "F.Cu" "F.Mask" "F.Paste")
			(net "HSC_TYPE_ADC")
		)
		(pad "18" smd rect
			(at 2.109978 1.500124 90)
			(size 0.6096 1.651)
			(layers "F.Cu" "F.Mask" "F.Paste")
			(net "SMB_SML1_PMBUS_HSC_R1_SCL")
		)
		(pad "19" smd rect
			(at 2.109978 2.500122 90)
			(size 0.6096 1.651)
			(layers "F.Cu" "F.Mask" "F.Paste")
			(net "SMB_SML1_PMBUS_HSC_R1_SDA")
		)
		(pad "20" smd rect
			(at 2.109978 3.50012 90)
			(size 0.6096 1.651)
			(layers "F.Cu" "F.Mask" "F.Paste")
			(net "IRQ_SML1_PMBUS_ALERT_N")
		)
		(pad "21" smd rect
			(at 2.109978 4.500118 90)
			(size 0.6096 1.651)
			(layers "F.Cu" "F.Mask" "F.Paste")
			(net "GND")
		)
		(pad "G1" smd circle
			(at 0 -6.720078 90)
			(size 0 0)
			(layers "F.Cu" "F.Mask" "F.Paste")
			(net "GND")
		)
		(pad "G2" smd circle
			(at 0 6.720078 90)
			(size 0 0)
			(layers "F.Cu" "F.Mask" "F.Paste")
			(net "GND")
		)
		(zone
			(layers "F.Cu" "B.Cu" "In1.Cu" "In2.Cu" "In3.Cu" "In4.Cu" "In5.Cu" "In6.Cu"
				"In7.Cu" "In8.Cu" "In9.Cu" "In10.Cu" "In11.Cu" "In12.Cu" "In13.Cu" "In14.Cu"
				"In15.Cu" "In16.Cu"
			)
			(hatch none 0.5)
			(connect_pads
				(clearance 0)
			)
			(min_thickness 0.25)
			(keepout
				(tracks not_allowed)
				(vias allowed)
				(pads allowed)
				(copperpour not_allowed)
				(footprints allowed)
			)
			(placement
				(enabled no)
				(sheetname "")
			)
			(fill
				(thermal_gap 0.5)
				(thermal_bridge_width 0.5)
				(island_removal_mode 0)
			)
			(polygon
				(pts
					(arc
						(start 195.678806 -388.685024)
						(mid 193.900806 -388.685024)
						(end 195.678806 -388.685024)
					)
				)
			)
		)
		(zone
			(layers "F.Cu" "B.Cu" "In1.Cu" "In2.Cu" "In3.Cu" "In4.Cu" "In5.Cu" "In6.Cu"
				"In7.Cu" "In8.Cu" "In9.Cu" "In10.Cu" "In11.Cu" "In12.Cu" "In13.Cu" "In14.Cu"
				"In15.Cu" "In16.Cu"
			)
			(hatch none 0.5)
			(connect_pads
				(clearance 0)
			)
			(min_thickness 0.25)
			(keepout
				(tracks not_allowed)
				(vias allowed)
				(pads allowed)
				(copperpour not_allowed)
				(footprints allowed)
			)
			(placement
				(enabled no)
				(sheetname "")
			)
			(fill
				(thermal_gap 0.5)
				(thermal_bridge_width 0.5)
				(island_removal_mode 0)
			)
			(polygon
				(pts
					(arc
						(start 195.678806 -377.636024)
						(mid 193.900806 -377.636024)
						(end 195.678806 -377.636024)
					)
				)
			)
		)
	)
)
